# T6G (Grand Teton) — schematic netlist excerpt (pin names and nets, part order shuffled) for the footprints in the layout excerpt that follows; sources: Cadence DE-HDL packaged netlist, KiCad conversion of 04192023_DAF0TMB3IC0_F0TG_MB_C_brd_V02_OCP.brd

R6902  Q_RES  0 5% CHIP  pkg 0201LF  page 354 : A = NCF_A1_CPU1_P3_GND ; B = GND
PR33  Q_RES  0 5% CHIP  pkg 0402LF  page 207 : A = NC_PVDD11_S3_P0_IMON4 ; B = GND
C697  Q_CAP_DIFFBUS  DIFF BUS_0.22UF 6.3V 20% X6S  pkg C0201  page 67 : \1\ = P5E_CPU1_G1_TX_C_DP<6> ; \2\ = P5E_CPU1_G1_TX_DP<6>
C1541  Q_CAP_DIFFBUS  DIFF BUS_0.22UF 6.3V 20% X6S  pkg C0201  page 67 : \1\ = P5E_CPU1_P3_TX_C_DP<3> ; \2\ = P5E_CPU1_P3_TX_DP<3>

(kicad_pcb
	(version 20260206)
	(generator "pcbnew")
	(generator_version "10.0")
	(general
		(thickness 1.6)
		(legacy_teardrops no)
	)
	(paper "A4")
	(title_block
		(title "04192023_DAF0TMB3IC0_F0TG_MB_C_brd_V02_OCP.brd")
		(comment 1 "Grand Teton / footprints 1452-1455 of 8354")
	)
	(layers
		(0 "F.Cu" signal "TOP")
		(4 "In1.Cu" signal "GND")
		(6 "In2.Cu" signal "IN1")
		(8 "In3.Cu" signal "GND1")
		(10 "In4.Cu" signal "IN2")
		(12 "In5.Cu" signal "GND2")
		(14 "In6.Cu" signal "IN3")
		(16 "In7.Cu" signal "GND3")
		(18 "In8.Cu" signal "VCC")
		(20 "In9.Cu" signal "VCC1")
		(22 "In10.Cu" signal "GND4")
		(24 "In11.Cu" signal "IN4")
		(26 "In12.Cu" signal "GND5")
		(28 "In13.Cu" signal "IN5")
		(30 "In14.Cu" signal "GND6")
		(32 "In15.Cu" signal "IN6")
		(34 "In16.Cu" signal "GND7")
		(2 "B.Cu" signal "BOTTOM")
		(9 "F.Adhes" user "F.Adhesive")
		(11 "B.Adhes" user "B.Adhesive")
		(13 "F.Paste" user "Package Geometry/Pastemask Top")
		(15 "B.Paste" user "Package Geometry/Pastemask Bottom")
		(5 "F.SilkS" user "Ref Des/Silkscreen Top")
		(7 "B.SilkS" user "Ref Des/Silkscreen Bottom")
		(1 "F.Mask" user "Board Geometry/Soldermask Top")
		(3 "B.Mask" user "Board Geometry/Soldermask Bottom")
		(17 "Dwgs.User" user "User.Drawings")
		(19 "Cmts.User" user "User.Comments")
		(21 "Eco1.User" user "User.Eco1")
		(23 "Eco2.User" user "User.Eco2")
		(25 "Edge.Cuts" user "Board Geometry/Outline")
		(27 "Margin" user)
		(31 "F.CrtYd" user "Package Geometry/Place Bound Top")
		(29 "B.CrtYd" user "Package Geometry/Place Bound Bottom")
		(35 "F.Fab" user "Ref Des/Assembly Top")
		(33 "B.Fab" user "Ref Des/Assembly Bottom")
	)
	(footprint ""
		(layer "F.Cu")
		(at 419.868096 -357.688134 -90)
		(property "Reference" "PR33"
			(at 0 0 270)
			(layer "F.SilkS")
			(hide yes)
			(effects
				(font
					(size 1.27 1.27)
				)
			)
		)
		(property "Value" ""
			(at 0 0 270)
			(layer "F.Fab")
			(effects
				(font
					(size 1.27 1.27)
				)
			)
		)
		(duplicate_pad_numbers_are_jumpers no)
		(fp_line
			(start -0.7874 0.4064)
			(end -0.7874 -0.4064)
			(stroke
				(width 0.1524)
				(type default)
			)
			(layer "F.SilkS")
		)
		(fp_line
			(start 0.7874 0.4064)
			(end -0.7874 0.4064)
			(stroke
				(width 0.1524)
				(type default)
			)
			(layer "F.SilkS")
		)
		(fp_line
			(start -0.7874 -0.4064)
			(end 0.7874 -0.4064)
			(stroke
				(width 0.1524)
				(type default)
			)
			(layer "F.SilkS")
		)
		(fp_line
			(start 0.7874 -0.4064)
			(end 0.7874 0.4064)
			(stroke
				(width 0.1524)
				(type default)
			)
			(layer "F.SilkS")
		)
		(fp_line
			(start -0.67945 0.3048)
			(end -0.67945 -0.305054)
			(stroke
				(width 0.1)
				(type default)
			)
			(layer "F.Fab")
		)
		(fp_line
			(start -0.12065 0.3048)
			(end -0.67945 0.3048)
			(stroke
				(width 0.1)
				(type default)
			)
			(layer "F.Fab")
		)
		(fp_line
			(start 0.120396 0.3048)
			(end 0.120396 0.2794)
			(stroke
				(width 0.1)
				(type default)
			)
			(layer "F.Fab")
		)
		(fp_line
			(start 0.67945 0.3048)
			(end 0.120396 0.3048)
			(stroke
				(width 0.1)
				(type default)
			)
			(layer "F.Fab")
		)
		(fp_line
			(start -0.12065 0.2794)
			(end -0.12065 0.3048)
			(stroke
				(width 0.1)
				(type default)
			)
			(layer "F.Fab")
		)
		(fp_line
			(start 0.120396 0.2794)
			(end -0.12065 0.2794)
			(stroke
				(width 0.1)
				(type default)
			)
			(layer "F.Fab")
		)
		(fp_line
			(start -0.12065 -0.2794)
			(end 0.12065 -0.2794)
			(stroke
				(width 0.1)
				(type default)
			)
			(layer "F.Fab")
		)
		(fp_line
			(start 0.12065 -0.2794)
			(end 0.12065 -0.3048)
			(stroke
				(width 0.1)
				(type default)
			)
			(layer "F.Fab")
		)
		(fp_line
			(start 0.12065 -0.3048)
			(end 0.67945 -0.3048)
			(stroke
				(width 0.1)
				(type default)
			)
			(layer "F.Fab")
		)
		(fp_line
			(start 0.67945 -0.3048)
			(end 0.67945 0.3048)
			(stroke
				(width 0.1)
				(type default)
			)
			(layer "F.Fab")
		)
		(fp_line
			(start -0.67945 -0.305054)
			(end -0.12065 -0.305054)
			(stroke
				(width 0.1)
				(type default)
			)
			(layer "F.Fab")
		)
		(fp_line
			(start -0.12065 -0.305054)
			(end -0.12065 -0.2794)
			(stroke
				(width 0.1)
				(type default)
			)
			(layer "F.Fab")
		)
		(pad "1" smd circle
			(at -0.40005 0 270)
			(size 0 0)
			(layers "F.Cu" "F.Mask" "F.Paste")
			(net "NC_PVDD11_S3_P0_IMON4")
		)
		(pad "2" smd circle
			(at 0.40005 0 270)
			(size 0 0)
			(layers "F.Cu" "F.Mask" "F.Paste")
			(net "GND")
		)
	)
	(footprint ""
		(layer "F.Cu")
		(at 41.874694 -17.623536 90)
		(property "Reference" "C697"
			(at 0 0 90)
			(layer "F.SilkS")
			(hide yes)
			(effects
				(font
					(size 1.27 1.27)
				)
			)
		)
		(property "Value" ""
			(at 0 0 90)
			(layer "F.Fab")
			(effects
				(font
					(size 1.27 1.27)
				)
			)
		)
		(duplicate_pad_numbers_are_jumpers no)
		(fp_line
			(start 0.299974 -0.150114)
			(end 0.299974 0.150114)
			(stroke
				(width 0.1)
				(type default)
			)
			(layer "F.Fab")
		)
		(fp_line
			(start -0.299974 -0.150114)
			(end 0.299974 -0.150114)
			(stroke
				(width 0.1)
				(type default)
			)
			(layer "F.Fab")
		)
		(fp_line
			(start 0.299974 0.150114)
			(end -0.299974 0.150114)
			(stroke
				(width 0.1)
				(type default)
			)
			(layer "F.Fab")
		)
		(fp_line
			(start -0.299974 0.150114)
			(end -0.299974 -0.150114)
			(stroke
				(width 0.1)
				(type default)
			)
			(layer "F.Fab")
		)
		(pad "1" smd rect
			(at -0.2667 0 90)
			(size 0.3048 0.381)
			(layers "F.Cu" "F.Mask" "F.Paste")
			(net "P5E_CPU1_G1_TX_C_DP<6>")
		)
		(pad "2" smd rect
			(at 0.2667 0 90)
			(size 0.3048 0.381)
			(layers "F.Cu" "F.Mask" "F.Paste")
			(net "P5E_CPU1_G1_TX_DP<6>")
		)
	)
	(footprint ""
		(layer "F.Cu")
		(at 111.791496 -370.57203 -90)
		(property "Reference" "C1541"
			(at 0 0 270)
			(layer "F.SilkS")
			(hide yes)
			(effects
				(font
					(size 1.27 1.27)
				)
			)
		)
		(property "Value" ""
			(at 0 0 270)
			(layer "F.Fab")
			(effects
				(font
					(size 1.27 1.27)
				)
			)
		)
		(duplicate_pad_numbers_are_jumpers no)
		(fp_line
			(start -0.299974 0.150114)
			(end -0.299974 -0.150114)
			(stroke
				(width 0.1)
				(type default)
			)
			(layer "F.Fab")
		)
		(fp_line
			(start 0.299974 0.150114)
			(end -0.299974 0.150114)
			(stroke
				(width 0.1)
				(type default)
			)
			(layer "F.Fab")
		)
		(fp_line
			(start -0.299974 -0.150114)
			(end 0.299974 -0.150114)
			(stroke
				(width 0.1)
				(type default)
			)
			(layer "F.Fab")
		)
		(fp_line
			(start 0.299974 -0.150114)
			(end 0.299974 0.150114)
			(stroke
				(width 0.1)
				(type default)
			)
			(layer "F.Fab")
		)
		(pad "1" smd rect
			(at -0.2667 0 270)
			(size 0.3048 0.381)
			(layers "F.Cu" "F.Mask" "F.Paste")
			(net "P5E_CPU1_P3_TX_C_DP<3>")
		)
		(pad "2" smd rect
			(at 0.2667 0 270)
			(size 0.3048 0.381)
			(layers "F.Cu" "F.Mask" "F.Paste")
			(net "P5E_CPU1_P3_TX_DP<3>")
		)
	)
	(footprint ""
		(layer "F.Cu")
		(at 136.803638 -391.051288)
		(property "Reference" "R6902"
			(at 0 0 0)
			(layer "F.SilkS")
			(hide yes)
			(effects
				(font
					(size 1.27 1.27)
				)
			)
		)
		(property "Value" ""
			(at 0 0 0)
			(layer "F.Fab")
			(effects
				(font
					(size 1.27 1.27)
				)
			)
		)
		(duplicate_pad_numbers_are_jumpers no)
		(fp_line
			(start -0.32512 -0.175006)
			(end 0.32512 -0.175006)
			(stroke
				(width 0.1)
				(type default)
			)
			(layer "F.Fab")
		)
		(fp_line
			(start -0.32512 0.175006)
			(end -0.32512 -0.175006)
			(stroke
				(width 0.1)
				(type default)
			)
			(layer "F.Fab")
		)
		(fp_line
			(start 0.32512 -0.175006)
			(end 0.32512 0.175006)
			(stroke
				(width 0.1)
				(type default)
			)
			(layer "F.Fab")
		)
		(fp_line
			(start 0.32512 0.175006)
			(end -0.32512 0.175006)
			(stroke
				(width 0.1)
				(type default)
			)
			(layer "F.Fab")
		)
		(pad "1" smd rect
			(at -0.2667 0)
			(size 0.3048 0.381)
			(layers "F.Cu" "F.Mask" "F.Paste")
			(net "NCF_A1_CPU1_P3_GND")
		)
		(pad "2" smd rect
			(at 0.2667 0 180)
			(size 0.3048 0.381)
			(layers "F.Cu" "F.Mask" "F.Paste")
			(net "GND")
		)
	)
)
